(kicad_pcb
	(version 20260206)
	(generator "pcbnew")
	(generator_version "10.0")
	(general
		(thickness 1.6)
		(legacy_teardrops no)
	)
	(paper "A4")
	(title_block
		(title "fcb — Lightning_FCB_BRD.brd")
		(comment 1 "Lightning (Wiwynn / Facebook NVMe JBOF) / footprints 232-238 of 495")
	)
	(layers
		(0 "F.Cu" signal "TOP")
		(4 "In1.Cu" signal "L2GND")
		(6 "In2.Cu" signal "L3VCC")
		(2 "B.Cu" signal "BOTTOM")
		(9 "F.Adhes" user "F.Adhesive")
		(11 "B.Adhes" user "B.Adhesive")
		(13 "F.Paste" user "Package Geometry/Pastemask Top")
		(15 "B.Paste" user "Package Geometry/Pastemask Bottom")
		(5 "F.SilkS" user "Ref Des/Silkscreen Top")
		(7 "B.SilkS" user "Ref Des/Silkscreen Bottom")
		(1 "F.Mask" user "Board Geometry/Soldermask Top")
		(3 "B.Mask" user "Board Geometry/Soldermask Bottom")
		(17 "Dwgs.User" user "User.Drawings")
		(19 "Cmts.User" user "User.Comments")
		(21 "Eco1.User" user "User.Eco1")
		(23 "Eco2.User" user "User.Eco2")
		(25 "Edge.Cuts" user "Board Geometry/Outline")
		(27 "Margin" user)
		(31 "F.CrtYd" user "Package Geometry/Place Bound Top")
		(29 "B.CrtYd" user "Package Geometry/Place Bound Bottom")
		(35 "F.Fab" user "Ref Des/Assembly Top")
		(33 "B.Fab" user "Ref Des/Assembly Bottom")
	)
	(footprint ""
		(layer "F.Cu")
		(at 40.999918 -450.44995 90)
		(property "Reference" "PAD2"
			(at 0 0 90)
			(layer "F.SilkS")
			(hide yes)
			(effects
				(font
					(size 1.27 1.27)
				)
			)
		)
		(property "Value" "PAD-1P-424137-1-OG-GP"
			(at -22.9743 -0.4572 90)
			(unlocked yes)
			(layer "F.Fab")
			(hide yes)
			(effects
				(font
					(size 1.016 1.016)
					(thickness 0.1524)
				)
			)
		)
		(property "Device Type" "PAD-1P-424137-1-OG"
			(at -22.9743 -1.9812 90)
			(unlocked yes)
			(layer "F.Fab")
			(hide yes)
			(effects
				(font
					(size 1.016 1.016)
					(thickness 0.1524)
				)
			)
		)
		(duplicate_pad_numbers_are_jumpers no)
		(fp_line
			(start 21.4503 -7.0993)
			(end 21.4503 7.0993)
			(stroke
				(width 0.1524)
				(type default)
			)
			(layer "F.SilkS")
		)
		(fp_line
			(start 2.816098 -7.0993)
			(end 21.4503 -7.0993)
			(stroke
				(width 0.1524)
				(type default)
			)
			(layer "F.SilkS")
		)
		(fp_line
			(start -0.075946 -7.0993)
			(end -0.075946 -5.750052)
			(stroke
				(width 0.1524)
				(type default)
			)
			(layer "F.SilkS")
		)
		(fp_line
			(start -21.4503 -7.0993)
			(end -0.075946 -7.0993)
			(stroke
				(width 0.1524)
				(type default)
			)
			(layer "F.SilkS")
		)
		(fp_line
			(start 2.816098 -5.750052)
			(end 2.816098 -7.0993)
			(stroke
				(width 0.1524)
				(type default)
			)
			(layer "F.SilkS")
		)
		(fp_line
			(start 21.4503 7.0993)
			(end -21.4503 7.0993)
			(stroke
				(width 0.1524)
				(type default)
			)
			(layer "F.SilkS")
		)
		(fp_line
			(start -21.4503 7.0993)
			(end -21.4503 -7.0993)
			(stroke
				(width 0.1524)
				(type default)
			)
			(layer "F.SilkS")
		)
		(fp_arc
			(start 2.816098 -5.750052)
			(mid 1.37008 -4.30403)
			(end -0.075946 -5.750052)
			(stroke
				(width 0.1524)
				(type default)
			)
			(layer "F.SilkS")
		)
		(fp_poly
			(pts
				(xy -21.7043 7.3533) (xy -21.7043 -7.3533) (xy 0.178054 -7.3533)
				(arc
					(start 0.178054 -5.750052)
					(mid 1.370076 -4.55803)
					(end 2.562098 -5.750052)
				)
				(xy 2.562098 -7.3533) (xy 21.7043 -7.3533) (xy 21.7043 7.3533)
			)
			(stroke
				(width 0)
				(type default)
			)
			(fill no)
			(layer "F.CrtYd")
		)
		(fp_poly
			(pts
				(xy -21.7043 7.3533) (xy -21.7043 -7.3533) (xy 0.178054 -7.3533)
				(arc
					(start 0.178054 -5.750052)
					(mid 1.370076 -4.55803)
					(end 2.562098 -5.750052)
				)
				(xy 2.562098 -7.3533) (xy 21.7043 -7.3533) (xy 21.7043 7.3533)
			)
			(stroke
				(width 0)
				(type default)
			)
			(fill no)
			(layer "F.Fab")
		)
		(pad "1" smd custom
			(at 0 0 90)
			(size 3.425063 3.425063)
			(layers "F.Cu" "F.Mask" "F.Paste")
			(net "GND")
			(options
				(clearance outline)
				(anchor circle)
			)
			(primitives
				(gr_poly
					(pts
						(xy -0.329946 -6.850126) (xy -21.20011 -6.850126) (xy -21.20011 6.850126) (xy 21.20011 6.850126)
						(xy 21.20011 -6.850126) (xy 3.070098 -6.850126)
						(arc
							(start 3.070098 -5.750052)
							(mid 1.370076 -4.05003)
							(end -0.329946 -5.750052)
						)
					)
					(width 0)
					(fill yes)
				)
			)
		)
	)
	(footprint ""
		(layer "F.Cu")
		(at 15.113 -55.118 90)
		(property "Reference" "R358"
			(at 0 0 90)
			(layer "F.SilkS")
			(hide yes)
			(effects
				(font
					(size 1.27 1.27)
				)
			)
		)
		(property "Value" "10KR2F-2-GP"
			(at 0.064008 -3.993896 90)
			(unlocked yes)
			(layer "F.Fab")
			(hide yes)
			(effects
				(font
					(size 1.016 1.016)
					(thickness 0.1524)
				)
			)
		)
		(property "Device Type" "R402H16"
			(at 0.064008 -5.517896 90)
			(unlocked yes)
			(layer "F.Fab")
			(hide yes)
			(effects
				(font
					(size 1.016 1.016)
					(thickness 0.1524)
				)
			)
		)
		(duplicate_pad_numbers_are_jumpers no)
		(fp_line
			(start 0.508 -0.9398)
			(end -0.508 -0.9398)
			(stroke
				(width 0.1524)
				(type default)
			)
			(layer "F.SilkS")
		)
		(fp_line
			(start -0.508 -0.9398)
			(end -0.508 0.9398)
			(stroke
				(width 0.1524)
				(type default)
			)
			(layer "F.SilkS")
		)
		(fp_rect
			(start -0.508 0.9398)
			(end 0.508 -0.9398)
			(stroke
				(width 0)
				(type default)
			)
			(fill no)
			(layer "F.CrtYd")
		)
		(fp_rect
			(start -0.508 0.9398)
			(end 0.508 -0.9398)
			(stroke
				(width 0)
				(type default)
			)
			(fill no)
			(layer "F.Fab")
		)
		(pad "1" smd custom
			(at 0 -0.4445 90)
			(size 0.1397 0.1397)
			(layers "F.Cu" "F.Mask" "F.Paste")
			(net "P3V3")
			(options
				(clearance outline)
				(anchor circle)
			)
			(primitives
				(gr_poly
					(pts
						(arc
							(start -0.1778 -0.2794)
							(mid -0.249642 -0.249642)
							(end -0.2794 -0.1778)
						)
						(arc
							(start -0.2794 0.1778)
							(mid -0.249642 0.249642)
							(end -0.1778 0.2794)
						)
						(arc
							(start 0.1778 0.2794)
							(mid 0.249642 0.249642)
							(end 0.2794 0.1778)
						)
						(arc
							(start 0.2794 -0.1778)
							(mid 0.249642 -0.249642)
							(end 0.1778 -0.2794)
						)
					)
					(width 0)
					(fill yes)
				)
			)
		)
		(pad "2" smd custom
			(at 0 0.4445 90)
			(size 0.1397 0.1397)
			(layers "F.Cu" "F.Mask" "F.Paste")
			(net "LOWER_TRAY_ID")
			(options
				(clearance outline)
				(anchor circle)
			)
			(primitives
				(gr_poly
					(pts
						(arc
							(start -0.1778 -0.2794)
							(mid -0.249642 -0.249642)
							(end -0.2794 -0.1778)
						)
						(arc
							(start -0.2794 0.1778)
							(mid -0.249642 0.249642)
							(end -0.1778 0.2794)
						)
						(arc
							(start 0.1778 0.2794)
							(mid 0.249642 0.249642)
							(end 0.2794 0.1778)
						)
						(arc
							(start 0.2794 -0.1778)
							(mid 0.249642 -0.249642)
							(end 0.1778 -0.2794)
						)
					)
					(width 0)
					(fill yes)
				)
			)
		)
	)
	(footprint ""
		(layer "F.Cu")
		(at 21.209 -371.729)
		(property "Reference" "PR33"
			(at 0 0 0)
			(layer "F.SilkS")
			(hide yes)
			(effects
				(font
					(size 1.27 1.27)
				)
			)
		)
		(property "Value" "51KR2F-L-GP"
			(at 0.064008 -3.993896 0)
			(unlocked yes)
			(layer "F.Fab")
			(hide yes)
			(effects
				(font
					(size 1.016 1.016)
					(thickness 0.1524)
				)
			)
		)
		(property "Device Type" "R402H16"
			(at 0.064008 -5.517896 0)
			(unlocked yes)
			(layer "F.Fab")
			(hide yes)
			(effects
				(font
					(size 1.016 1.016)
					(thickness 0.1524)
				)
			)
		)
		(duplicate_pad_numbers_are_jumpers no)
		(fp_line
			(start -0.508 -0.9398)
			(end -0.508 0.9398)
			(stroke
				(width 0.1524)
				(type default)
			)
			(layer "F.SilkS")
		)
		(fp_line
			(start 0.508 -0.9398)
			(end -0.508 -0.9398)
			(stroke
				(width 0.1524)
				(type default)
			)
			(layer "F.SilkS")
		)
		(fp_rect
			(start -0.508 0.9398)
			(end 0.508 -0.9398)
			(stroke
				(width 0)
				(type default)
			)
			(fill no)
			(layer "F.CrtYd")
		)
		(fp_rect
			(start -0.508 0.9398)
			(end 0.508 -0.9398)
			(stroke
				(width 0)
				(type default)
			)
			(fill no)
			(layer "F.Fab")
		)
		(pad "1" smd custom
			(at 0 -0.4445)
			(size 0.1397 0.1397)
			(layers "F.Cu" "F.Mask" "F.Paste")
			(net "P12V_AUX")
			(options
				(clearance outline)
				(anchor circle)
			)
			(primitives
				(gr_poly
					(pts
						(arc
							(start -0.1778 -0.2794)
							(mid -0.249642 -0.249642)
							(end -0.2794 -0.1778)
						)
						(arc
							(start -0.2794 0.1778)
							(mid -0.249642 0.249642)
							(end -0.1778 0.2794)
						)
						(arc
							(start 0.1778 0.2794)
							(mid 0.249642 0.249642)
							(end 0.2794 0.1778)
						)
						(arc
							(start 0.2794 -0.1778)
							(mid 0.249642 -0.249642)
							(end 0.1778 -0.2794)
						)
					)
					(width 0)
					(fill yes)
				)
			)
		)
		(pad "2" smd custom
			(at 0 0.4445)
			(size 0.1397 0.1397)
			(layers "F.Cu" "F.Mask" "F.Paste")
			(net "ADM1276_OV")
			(options
				(clearance outline)
				(anchor circle)
			)
			(primitives
				(gr_poly
					(pts
						(arc
							(start -0.1778 -0.2794)
							(mid -0.249642 -0.249642)
							(end -0.2794 -0.1778)
						)
						(arc
							(start -0.2794 0.1778)
							(mid -0.249642 0.249642)
							(end -0.1778 0.2794)
						)
						(arc
							(start 0.1778 0.2794)
							(mid 0.249642 0.249642)
							(end 0.2794 0.1778)
						)
						(arc
							(start 0.2794 -0.1778)
							(mid 0.249642 -0.249642)
							(end 0.1778 -0.2794)
						)
					)
					(width 0)
					(fill yes)
				)
			)
		)
	)
	(footprint ""
		(layer "F.Cu")
		(at 35.6616 -144.6784 180)
		(property "Reference" "PC92"
			(at 0 0 180)
			(layer "F.SilkS")
			(hide yes)
			(effects
				(font
					(size 1.27 1.27)
				)
			)
		)
		(property "Value" "SCD01U50V3KX-4GP"
			(at 0 -2.8194 180)
			(unlocked yes)
			(layer "F.Fab")
			(hide yes)
			(effects
				(font
					(size 1.016 1.016)
					(thickness 0.1524)
				)
			)
		)
		(property "Device Type" "C603H36"
			(at 0 -4.3434 180)
			(unlocked yes)
			(layer "F.Fab")
			(hide yes)
			(effects
				(font
					(size 1.016 1.016)
					(thickness 0.1524)
				)
			)
		)
		(duplicate_pad_numbers_are_jumpers no)
		(fp_line
			(start 0.508 0)
			(end -0.508 0)
			(stroke
				(width 0.2032)
				(type default)
			)
			(layer "F.SilkS")
		)
		(fp_rect
			(start -0.5842 1.3335)
			(end 0.5842 -1.3335)
			(stroke
				(width 0)
				(type default)
			)
			(fill no)
			(layer "F.CrtYd")
		)
		(fp_rect
			(start -0.5842 1.3335)
			(end 0.5842 -1.3335)
			(stroke
				(width 0)
				(type default)
			)
			(fill no)
			(layer "F.Fab")
		)
		(pad "1" smd custom
			(at 0 -0.762 180)
			(size 0.2159 0.2159)
			(layers "F.Cu" "F.Mask" "F.Paste")
			(net "P12VL_2490_TIMER")
			(options
				(clearance outline)
				(anchor circle)
			)
			(primitives
				(gr_poly
					(pts
						(arc
							(start -0.3302 -0.4318)
							(mid -0.402042 -0.402042)
							(end -0.4318 -0.3302)
						)
						(arc
							(start -0.4318 0.3302)
							(mid -0.402042 0.402042)
							(end -0.3302 0.4318)
						)
						(arc
							(start 0.3302 0.4318)
							(mid 0.402042 0.402042)
							(end 0.4318 0.3302)
						)
						(arc
							(start 0.4318 -0.3302)
							(mid 0.402042 -0.402042)
							(end 0.3302 -0.4318)
						)
					)
					(width 0)
					(fill yes)
				)
			)
		)
		(pad "2" smd custom
			(at 0 0.762 180)
			(size 0.2159 0.2159)
			(layers "F.Cu" "F.Mask" "F.Paste")
			(net "GND")
			(options
				(clearance outline)
				(anchor circle)
			)
			(primitives
				(gr_poly
					(pts
						(arc
							(start -0.3302 -0.4318)
							(mid -0.402042 -0.402042)
							(end -0.4318 -0.3302)
						)
						(arc
							(start -0.4318 0.3302)
							(mid -0.402042 0.402042)
							(end -0.3302 0.4318)
						)
						(arc
							(start 0.3302 0.4318)
							(mid 0.402042 0.402042)
							(end 0.4318 0.3302)
						)
						(arc
							(start 0.4318 -0.3302)
							(mid 0.402042 -0.402042)
							(end 0.3302 -0.4318)
						)
					)
					(width 0)
					(fill yes)
				)
			)
		)
	)
	(footprint ""
		(layer "F.Cu")
		(at 28.702 -195.3514 90)
		(property "Reference" "C42"
			(at 0 0 90)
			(layer "F.SilkS")
			(hide yes)
			(effects
				(font
					(size 1.27 1.27)
				)
			)
		)
		(property "Value" "SC1U25V3KX-1-GP"
			(at 0 -2.8194 90)
			(unlocked yes)
			(layer "F.Fab")
			(hide yes)
			(effects
				(font
					(size 1.016 1.016)
					(thickness 0.1524)
				)
			)
		)
		(property "Device Type" "C603H36"
			(at 0 -4.3434 90)
			(unlocked yes)
			(layer "F.Fab")
			(hide yes)
			(effects
				(font
					(size 1.016 1.016)
					(thickness 0.1524)
				)
			)
		)
		(duplicate_pad_numbers_are_jumpers no)
		(fp_line
			(start 0.508 0)
			(end -0.508 0)
			(stroke
				(width 0.2032)
				(type default)
			)
			(layer "F.SilkS")
		)
		(fp_rect
			(start -0.5842 1.3335)
			(end 0.5842 -1.3335)
			(stroke
				(width 0)
				(type default)
			)
			(fill no)
			(layer "F.CrtYd")
		)
		(fp_rect
			(start -0.5842 1.3335)
			(end 0.5842 -1.3335)
			(stroke
				(width 0)
				(type default)
			)
			(fill no)
			(layer "F.Fab")
		)
		(pad "1" smd custom
			(at 0 -0.762 90)
			(size 0.2159 0.2159)
			(layers "F.Cu" "F.Mask" "F.Paste")
			(net "P12V")
			(options
				(clearance outline)
				(anchor circle)
			)
			(primitives
				(gr_poly
					(pts
						(arc
							(start -0.3302 -0.4318)
							(mid -0.402042 -0.402042)
							(end -0.4318 -0.3302)
						)
						(arc
							(start -0.4318 0.3302)
							(mid -0.402042 0.402042)
							(end -0.3302 0.4318)
						)
						(arc
							(start 0.3302 0.4318)
							(mid 0.402042 0.402042)
							(end 0.4318 0.3302)
						)
						(arc
							(start 0.4318 -0.3302)
							(mid 0.402042 -0.402042)
							(end 0.3302 -0.4318)
						)
					)
					(width 0)
					(fill yes)
				)
			)
		)
		(pad "2" smd custom
			(at 0 0.762 90)
			(size 0.2159 0.2159)
			(layers "F.Cu" "F.Mask" "F.Paste")
			(net "GND")
			(options
				(clearance outline)
				(anchor circle)
			)
			(primitives
				(gr_poly
					(pts
						(arc
							(start -0.3302 -0.4318)
							(mid -0.402042 -0.402042)
							(end -0.4318 -0.3302)
						)
						(arc
							(start -0.4318 0.3302)
							(mid -0.402042 0.402042)
							(end -0.3302 0.4318)
						)
						(arc
							(start 0.3302 0.4318)
							(mid 0.402042 0.402042)
							(end 0.4318 0.3302)
						)
						(arc
							(start 0.4318 -0.3302)
							(mid 0.402042 -0.402042)
							(end 0.3302 -0.4318)
						)
					)
					(width 0)
					(fill yes)
				)
			)
		)
	)
	(footprint ""
		(layer "F.Cu")
		(at 28.9814 -96.5454 -90)
		(property "Reference" "C24"
			(at 0 0 270)
			(layer "F.SilkS")
			(hide yes)
			(effects
				(font
					(size 1.27 1.27)
				)
			)
		)
		(property "Value" "SCD1U50V3KX-GP"
			(at 0 -2.8194 270)
			(unlocked yes)
			(layer "F.Fab")
			(hide yes)
			(effects
				(font
					(size 1.016 1.016)
					(thickness 0.1524)
				)
			)
		)
		(property "Device Type" "C603H36"
			(at 0 -4.3434 270)
			(unlocked yes)
			(layer "F.Fab")
			(hide yes)
			(effects
				(font
					(size 1.016 1.016)
					(thickness 0.1524)
				)
			)
		)
		(duplicate_pad_numbers_are_jumpers no)
		(fp_line
			(start 0.508 0)
			(end -0.508 0)
			(stroke
				(width 0.2032)
				(type default)
			)
			(layer "F.SilkS")
		)
		(fp_rect
			(start -0.5842 1.3335)
			(end 0.5842 -1.3335)
			(stroke
				(width 0)
				(type default)
			)
			(fill no)
			(layer "F.CrtYd")
		)
		(fp_rect
			(start -0.5842 1.3335)
			(end 0.5842 -1.3335)
			(stroke
				(width 0)
				(type default)
			)
			(fill no)
			(layer "F.Fab")
		)
		(pad "1" smd custom
			(at 0 -0.762 270)
			(size 0.2159 0.2159)
			(layers "F.Cu" "F.Mask" "F.Paste")
			(net "P12VL")
			(options
				(clearance outline)
				(anchor circle)
			)
			(primitives
				(gr_poly
					(pts
						(arc
							(start -0.3302 -0.4318)
							(mid -0.402042 -0.402042)
							(end -0.4318 -0.3302)
						)
						(arc
							(start -0.4318 0.3302)
							(mid -0.402042 0.402042)
							(end -0.3302 0.4318)
						)
						(arc
							(start 0.3302 0.4318)
							(mid 0.402042 0.402042)
							(end 0.4318 0.3302)
						)
						(arc
							(start 0.4318 -0.3302)
							(mid 0.402042 -0.402042)
							(end 0.3302 -0.4318)
						)
					)
					(width 0)
					(fill yes)
				)
			)
		)
		(pad "2" smd custom
			(at 0 0.762 270)
			(size 0.2159 0.2159)
			(layers "F.Cu" "F.Mask" "F.Paste")
			(net "GND")
			(options
				(clearance outline)
				(anchor circle)
			)
			(primitives
				(gr_poly
					(pts
						(arc
							(start -0.3302 -0.4318)
							(mid -0.402042 -0.402042)
							(end -0.4318 -0.3302)
						)
						(arc
							(start -0.4318 0.3302)
							(mid -0.402042 0.402042)
							(end -0.3302 0.4318)
						)
						(arc
							(start 0.3302 0.4318)
							(mid 0.402042 0.402042)
							(end 0.4318 0.3302)
						)
						(arc
							(start 0.4318 -0.3302)
							(mid 0.402042 -0.402042)
							(end 0.3302 -0.4318)
						)
					)
					(width 0)
					(fill yes)
				)
			)
		)
	)
	(footprint ""
		(layer "F.Cu")
		(at 29.3624 -167.259 180)
		(property "Reference" "R162"
			(at 0 0 180)
			(layer "F.SilkS")
			(hide yes)
			(effects
				(font
					(size 1.27 1.27)
				)
			)
		)
		(property "Value" "0R2J-2-GP"
			(at 0.064008 -3.993896 180)
			(unlocked yes)
			(layer "F.Fab")
			(hide yes)
			(effects
				(font
					(size 1.016 1.016)
					(thickness 0.1524)
				)
			)
		)
		(property "Device Type" "R402H16"
			(at 0.064008 -5.517896 180)
			(unlocked yes)
			(layer "F.Fab")
			(hide yes)
			(effects
				(font
					(size 1.016 1.016)
					(thickness 0.1524)
				)
			)
		)
		(duplicate_pad_numbers_are_jumpers no)
		(fp_line
			(start 0.508 -0.9398)
			(end -0.508 -0.9398)
			(stroke
				(width 0.1524)
				(type default)
			)
			(layer "F.SilkS")
		)
		(fp_line
			(start -0.508 -0.9398)
			(end -0.508 0.9398)
			(stroke
				(width 0.1524)
				(type default)
			)
			(layer "F.SilkS")
		)
		(fp_rect
			(start -0.508 0.9398)
			(end 0.508 -0.9398)
			(stroke
				(width 0)
				(type default)
			)
			(fill no)
			(layer "F.CrtYd")
		)
		(fp_rect
			(start -0.508 0.9398)
			(end 0.508 -0.9398)
			(stroke
				(width 0)
				(type default)
			)
			(fill no)
			(layer "F.Fab")
		)
		(pad "1" smd custom
			(at 0 -0.4445 180)
			(size 0.1397 0.1397)
			(layers "F.Cu" "F.Mask" "F.Paste")
			(net "NCT7904D_PWM2")
			(options
				(clearance outline)
				(anchor circle)
			)
			(primitives
				(gr_poly
					(pts
						(arc
							(start -0.1778 -0.2794)
							(mid -0.249642 -0.249642)
							(end -0.2794 -0.1778)
						)
						(arc
							(start -0.2794 0.1778)
							(mid -0.249642 0.249642)
							(end -0.1778 0.2794)
						)
						(arc
							(start 0.1778 0.2794)
							(mid 0.249642 0.249642)
							(end 0.2794 0.1778)
						)
						(arc
							(start 0.2794 -0.1778)
							(mid 0.249642 -0.249642)
							(end 0.1778 -0.2794)
						)
					)
					(width 0)
					(fill yes)
				)
			)
		)
		(pad "2" smd custom
			(at 0 0.4445 180)
			(size 0.1397 0.1397)
			(layers "F.Cu" "F.Mask" "F.Paste")
			(net "PWM_BUFFER_IN_FAN3_FAN4")
			(options
				(clearance outline)
				(anchor circle)
			)
			(primitives
				(gr_poly
					(pts
						(arc
							(start -0.1778 -0.2794)
							(mid -0.249642 -0.249642)
							(end -0.2794 -0.1778)
						)
						(arc
							(start -0.2794 0.1778)
							(mid -0.249642 0.249642)
							(end -0.1778 0.2794)
						)
						(arc
							(start 0.1778 0.2794)
							(mid 0.249642 0.249642)
							(end 0.2794 0.1778)
						)
						(arc
							(start 0.2794 -0.1778)
							(mid 0.249642 -0.249642)
							(end 0.1778 -0.2794)
						)
					)
					(width 0)
					(fill yes)
				)
			)
		)
	)
)
